# S9S_MB_2U (Grand Teton) — schematic netlist excerpt (pin names and nets, part order shuffled) for the footprints in the layout excerpt that follows; sources: Cadence DE-HDL packaged netlist, KiCad conversion of 03242023_DA0F0TMBIJ0_F0T_Motherboard_J_brd_V01_OCP.brd

C1034  Q_CAP  22UF 4V 20% X6S  pkg C0402  page 74 : A = PVCCIN_CPU0 ; B = GND

(kicad_pcb
	(version 20260206)
	(generator "pcbnew")
	(generator_version "10.0")
	(general
		(thickness 1.6)
		(legacy_teardrops no)
	)
	(paper "A4")
	(title_block
		(title "03242023_DA0F0TMBIJ0_F0T_Motherboard_J_brd_V01_OCP.brd")
		(comment 1 "Grand Teton / footprints 1951-1951 of 6105")
	)
	(layers
		(0 "F.Cu" signal "TOP")
		(4 "In1.Cu" signal "GND")
		(6 "In2.Cu" signal "IN1")
		(8 "In3.Cu" signal "GND1")
		(10 "In4.Cu" signal "IN2")
		(12 "In5.Cu" signal "GND2")
		(14 "In6.Cu" signal "IN3")
		(16 "In7.Cu" signal "GND3")
		(18 "In8.Cu" signal "VCC")
		(20 "In9.Cu" signal "VCC1")
		(22 "In10.Cu" signal "GND4")
		(24 "In11.Cu" signal "IN4")
		(26 "In12.Cu" signal "GND5")
		(28 "In13.Cu" signal "IN5")
		(30 "In14.Cu" signal "GND6")
		(32 "In15.Cu" signal "IN6")
		(34 "In16.Cu" signal "GND7")
		(2 "B.Cu" signal "BOTTOM")
		(9 "F.Adhes" user "F.Adhesive")
		(11 "B.Adhes" user "B.Adhesive")
		(13 "F.Paste" user "Package Geometry/Pastemask Top")
		(15 "B.Paste" user "Package Geometry/Pastemask Bottom")
		(5 "F.SilkS" user "Ref Des/Silkscreen Top")
		(7 "B.SilkS" user "Ref Des/Silkscreen Bottom")
		(1 "F.Mask" user "Board Geometry/Soldermask Top")
		(3 "B.Mask" user "Board Geometry/Soldermask Bottom")
		(17 "Dwgs.User" user "User.Drawings")
		(19 "Cmts.User" user "User.Comments")
		(21 "Eco1.User" user "User.Eco1")
		(23 "Eco2.User" user "User.Eco2")
		(25 "Edge.Cuts" user "Board Geometry/Outline")
		(27 "Margin" user)
		(31 "F.CrtYd" user "Package Geometry/Place Bound Top")
		(29 "B.CrtYd" user "Package Geometry/Place Bound Bottom")
		(35 "F.Fab" user "Ref Des/Assembly Top")
		(33 "B.Fab" user "Ref Des/Assembly Bottom")
	)
	(footprint ""
		(layer "F.Cu")
		(at 353.266248 -249.320304 -90)
		(property "Reference" "C1034"
			(at 0 0 270)
			(layer "F.SilkS")
			(hide yes)
			(effects
				(font
					(size 1.27 1.27)
				)
			)
		)
		(property "Value" ""
			(at 0 0 270)
			(layer "F.Fab")
			(effects
				(font
					(size 1.27 1.27)
				)
			)
		)
		(duplicate_pad_numbers_are_jumpers no)
		(fp_line
			(start -0.7874 0.4064)
			(end -0.7874 -0.4064)
			(stroke
				(width 0.1524)
				(type default)
			)
			(layer "F.SilkS")
		)
		(fp_line
			(start 0.7874 0.4064)
			(end -0.7874 0.4064)
			(stroke
				(width 0.1524)
				(type default)
			)
			(layer "F.SilkS")
		)
		(fp_line
			(start -0.7874 -0.4064)
			(end 0.7874 -0.4064)
			(stroke
				(width 0.1524)
				(type default)
			)
			(layer "F.SilkS")
		)
		(fp_line
			(start 0.7874 -0.4064)
			(end 0.7874 0.4064)
			(stroke
				(width 0.1524)
				(type default)
			)
			(layer "F.SilkS")
		)
		(fp_line
			(start -0.67945 0.3048)
			(end -0.67945 -0.305054)
			(stroke
				(width 0.1)
				(type default)
			)
			(layer "F.Fab")
		)
		(fp_line
			(start -0.12065 0.3048)
			(end -0.67945 0.3048)
			(stroke
				(width 0.1)
				(type default)
			)
			(layer "F.Fab")
		)
		(fp_line
			(start 0.120396 0.3048)
			(end 0.120396 0.2794)
			(stroke
				(width 0.1)
				(type default)
			)
			(layer "F.Fab")
		)
		(fp_line
			(start 0.67945 0.3048)
			(end 0.120396 0.3048)
			(stroke
				(width 0.1)
				(type default)
			)
			(layer "F.Fab")
		)
		(fp_line
			(start -0.12065 0.2794)
			(end -0.12065 0.3048)
			(stroke
				(width 0.1)
				(type default)
			)
			(layer "F.Fab")
		)
		(fp_line
			(start 0.120396 0.2794)
			(end -0.12065 0.2794)
			(stroke
				(width 0.1)
				(type default)
			)
			(layer "F.Fab")
		)
		(fp_line
			(start -0.12065 -0.2794)
			(end 0.12065 -0.2794)
			(stroke
				(width 0.1)
				(type default)
			)
			(layer "F.Fab")
		)
		(fp_line
			(start 0.12065 -0.2794)
			(end 0.12065 -0.3048)
			(stroke
				(width 0.1)
				(type default)
			)
			(layer "F.Fab")
		)
		(fp_line
			(start 0.12065 -0.3048)
			(end 0.67945 -0.3048)
			(stroke
				(width 0.1)
				(type default)
			)
			(layer "F.Fab")
		)
		(fp_line
			(start 0.67945 -0.3048)
			(end 0.67945 0.3048)
			(stroke
				(width 0.1)
				(type default)
			)
			(layer "F.Fab")
		)
		(fp_line
			(start -0.67945 -0.305054)
			(end -0.12065 -0.305054)
			(stroke
				(width 0.1)
				(type default)
			)
			(layer "F.Fab")
		)
		(fp_line
			(start -0.12065 -0.305054)
			(end -0.12065 -0.2794)
			(stroke
				(width 0.1)
				(type default)
			)
			(layer "F.Fab")
		)
		(pad "1" smd circle
			(at -0.40005 0 270)
			(size 0 0)
			(layers "F.Cu" "F.Mask" "F.Paste")
			(net "PVCCIN_CPU0")
		)
		(pad "2" smd circle
			(at 0.40005 0 270)
			(size 0 0)
			(layers "F.Cu" "F.Mask" "F.Paste")
			(net "GND")
		)
	)
)
